# T6G (Grand Teton) — schematic parts with pin connectivity, parts 6983–7132 of 8303; source: Cadence DE-HDL packaged netlist (pstxprt.dat, pstxnet.dat, pstchip.dat)

R3688  Q_RES  0 5% CHIP  pkg 0402LF  page 257 : 1 = P1V581_PDB_ADC ; 2 = P3V3_PDB_AUX_ADC_TIC
R3689  Q_RES  4.7K 1% EMPTY  pkg 0402LF  page 257 : 1 = P3V3_ADC128_VCC ; 2 = ADC128_VREF
R3690  Q_RES  4.7K 1% EMPTY  pkg 0402LF  page 257 : 1 = ADC128_VREF ; 2 = GND
R3703  Q_RES  10K 1% EMPTY  pkg 0402LF  page 252 : 1 = P3V3_AUX ; 2 = PCA9548_PCIE0_ADDR2
R3704  Q_RES  1K 1% CHIP  pkg 0402LF  page 252 : 1 = PCA9548_PCIE0_ADDR2 ; 2 = GND
R3705  Q_RES  10K 1% EMPTY  pkg 0402LF  page 252 : 1 = P3V3_AUX ; 2 = RST_SMB_SWITCH_N
R3706  Q_RES  10K 1% EMPTY  pkg 0402LF  page 252 : 1 = P3V3_AUX ; 2 = PCA9548_PCIE0_ADDR1
R3707  Q_RES  1K 1% CHIP  pkg 0402LF  page 252 : 1 = PCA9548_PCIE0_ADDR1 ; 2 = GND
R3708  Q_RES  10K 1% EMPTY  pkg 0402LF  page 252 : 1 = P3V3_AUX ; 2 = PCA9548_PCIE0_ADDR0
R3709  Q_RES  1K 1% CHIP  pkg 0402LF  page 252 : 1 = PCA9548_PCIE0_ADDR0 ; 2 = GND
R3710  Q_RES  0 5% CHIP  pkg 0402LF  page 252 : 1 = RST_SMB_SWITCH_N ; 2 = PU_RST_SMB_PCIE2_N
R3711  Q_RES  33.2 1% CHIP  pkg 0402LF  page 252 : 1 = SMB_VR_SENSOR_3V3AUX_SCL ; 2 = SMB_VR_SENSOR_3V3AUX_SCL_R
R3712  Q_RES  33.2 1% CHIP  pkg 0402LF  page 252 : 1 = SMB_VR_SENSOR_3V3AUX_SDA ; 2 = SMB_VR_SENSOR_3V3AUX_SDA_R
R3713  Q_RES  0 5% CHIP  pkg 0402LF  page 252 : 1 = SMB_VR_3V3AUX_SCL_R6 ; 2 = SMB_VR_3V3AUX_SCL
R3714  Q_RES  0 5% CHIP  pkg 0402LF  page 252 : 1 = SMB_VR_3V3AUX_SDA_R6 ; 2 = SMB_VR_3V3AUX_SDA
R3715  Q_RES  0 5% CHIP  pkg 0402LF  page 252 : 1 = SMB_LM75_0_3V3AUX_SCL_R ; 2 = SMB_LM75_0_3V3AUX_SCL
R3716  Q_RES  0 5% CHIP  pkg 0402LF  page 252 : 1 = SMB_LM75_0_3V3AUX_SDA_R ; 2 = SMB_LM75_0_3V3AUX_SDA
R3717  Q_RES  0 5% CHIP  pkg 0402LF  page 252 : 1 = SMB_LM75_1_3V3AUX_SCL_R ; 2 = SMB_LM75_1_3V3AUX_SCL
R3718  Q_RES  0 5% CHIP  pkg 0402LF  page 252 : 1 = SMB_LM75_1_3V3AUX_SDA_R ; 2 = SMB_LM75_1_3V3AUX_SDA
R3719  Q_RES  0 5% CHIP  pkg 0402LF  page 252 : 1 = SMB_LM75_2_3V3AUX_SCL_R ; 2 = SMB_LM75_2_3V3AUX_SCL
R3720  Q_RES  0 5% CHIP  pkg 0402LF  page 252 : 1 = SMB_LM75_2_3V3AUX_SDA_R ; 2 = SMB_LM75_2_3V3AUX_SDA
R3721  Q_RES  0 5% CHIP  pkg 0402LF  page 252 : 1 = SMB_LM75_3_3V3AUX_SCL_R ; 2 = SMB_LM75_3_3V3AUX_SCL
R3722  Q_RES  0 5% CHIP  pkg 0402LF  page 252 : 1 = SMB_LM75_3_3V3AUX_SDA_R ; 2 = SMB_LM75_3_3V3AUX_SDA
R3723  Q_RES  2.2K 5% CHIP  pkg 0402LF  page 252 : 1 = P3V3_AUX ; 2 = SMB_VR_3V3AUX_SCL
R3724  Q_RES  2.2K 5% CHIP  pkg 0402LF  page 252 : 1 = P3V3_AUX ; 2 = SMB_VR_3V3AUX_SDA
R3725  Q_RES  2.2K 5% CHIP  pkg 0402LF  page 252 : 1 = P3V3_AUX ; 2 = SMB_LM75_0_3V3AUX_SCL
R3726  Q_RES  2.2K 5% CHIP  pkg 0402LF  page 252 : 1 = P3V3_AUX ; 2 = SMB_LM75_0_3V3AUX_SDA
R3727  Q_RES  2.2K 5% CHIP  pkg 0402LF  page 252 : 1 = P3V3_AUX ; 2 = SMB_LM75_1_3V3AUX_SCL
R3728  Q_RES  2.2K 5% CHIP  pkg 0402LF  page 252 : 1 = P3V3_AUX ; 2 = SMB_LM75_1_3V3AUX_SDA
R3729  Q_RES  2.2K 5% CHIP  pkg 0402LF  page 252 : 1 = P3V3_AUX ; 2 = SMB_LM75_2_3V3AUX_SCL
R3730  Q_RES  2.2K 5% CHIP  pkg 0402LF  page 252 : 1 = P3V3_AUX ; 2 = SMB_LM75_2_3V3AUX_SDA
R3731  Q_RES  2.2K 5% CHIP  pkg 0402LF  page 252 : 1 = P3V3_AUX ; 2 = SMB_LM75_3_3V3AUX_SCL
R3732  Q_RES  2.2K 5% CHIP  pkg 0402LF  page 252 : 1 = P3V3_AUX ; 2 = SMB_LM75_3_3V3AUX_SDA
R3751  Q_RES  0 5% CHIP  pkg 0402LF  page 236 : 1 = INA230_2_A0 ; 2 = SMB_INA230_2_3V3AUX_SDA_R1
R3752  Q_RES  0 5% CHIP  pkg 0402LF  page 236 : 1 = E1S_0_P3V3_ADC_ALERT_R ; 2 = E1S_0_P3V3_P12V_ADC_R_ALERT
R3754  Q_RES  0 5% CHIP  pkg 0402LF  page 236 : 1 = SMB_INA230_2_3V3AUX_SCL_R ; 2 = SMB_INA230_2_3V3AUX_SCL_R1
R3756  Q_RES  0 5% CHIP  pkg 0402LF  page 236 : 1 = SMB_INA230_2_3V3AUX_SDA_R ; 2 = SMB_INA230_2_3V3AUX_SDA_R1
R3758  Q_RES  10 1% CHIP  pkg 0402LF  page 236 : 1 = P3V3_E1S_0_R ; 2 = VSENSE_P3V3_INA230_2_INP
R3760  Q_RES  10 1% CHIP  pkg 0402LF  page 236 : 1 = P3V3_E1S_0 ; 2 = VSENSE_P3V3_INA230_2_INN
R3763  Q_RES  4.7K 1% CHIP  pkg 0402LF  page 236 : 1 = GND ; 2 = INA230_2_A1
R3764  Q_RES  4.7K 1% EMPTY  pkg 0402LF  page 236 : 1 = GND ; 2 = INA230_2_A0
R3767  Q_RES  0.002 1% CHIP  pkg 2512LF  page 236 : 1 = P3V3_E1S_0 ; 2 = P3V3_E1S_0_R
R3770  Q_RES  0 5% CHIP  pkg 0402LF  page 241 : 1 = GPU_PRSNT ; 2 = GPU_PRSNT_R
R3771  Q_RES  10K 1% CHIP  pkg 0402LF  page 145 : 1 = P3V3_AUX ; 2 = E1S_0_PWRDIS
R3772  Q_RES  0 5% CHIP  pkg 0402LF  page 145 : 1 = RST_SMB_BUF_E1S_0_N ; 2 = RST_SMB_E1S_0_N
R3773  Q_RES  4.7K 5% EMPTY  pkg 0402LF  page 145 : 1 = P3V3_AUX ; 2 = RST_SMB_E1S_0_N
R3775  Q_RES  0 5% CHIP  pkg 0402LF  page 145 : 1 = FM_SMB_RST_E1S_0_R_N ; 2 = RST_SMB_E1S_N
R3776  Q_RES  0 5% CHIP  pkg 0402LF  page 150 : 1 = FM_UARTSW_MSB_N ; 2 = FM_UARTSW_MSB_R
R3777  Q_RES  0 5% CHIP  pkg 0402LF  page 150 : 1 = FM_UARTSW_LSB_N ; 2 = FM_UARTSW_LSB_R
R3778  Q_RES  0 5% CHIP  pkg 0402LF  page 150 : 1 = FM_SOL_UART_CH_SEL_R ; 2 = FM_SOL_UART_CH_SEL
R3779  Q_RES  0 5% CHIP  pkg 0402LF  page 145 : 1 = RST_PERST_E1S_0_N ; 2 = RST_PCIE_E1S_PERST_N
R3783  Q_RES  100K 1% EMPTY  pkg 0402LF  page 134 : 1 = P3V3_AUX ; 2 = OCP_V3_1_P3V3_PWRGD
R3784  Q_RES  0 5% CHIP  pkg 0402LF  page 134 : 1 = P12V_OCP_UV_1_R ; 2 = P12V_OCP_UV_1
R3785  Q_RES  0 5% CHIP  pkg 0402LF  page 134 : 1 = P3V3_OCP_UV_1_R1 ; 2 = P3V3_OCP_UV_1
R3794  Q_RES  0 5% EMPTY  pkg 0402LF  page 134 : 1 = P3V3_OCP_PWRGD_1 ; 2 = OCP_V3_1_P3V3_PWRGD
R3796  Q_RES  100K 1% CHIP  pkg 0402LF  page 134 : 1 = P3V3_AUX ; 2 = P3V3_OCP_FAULT_1
R3797  Q_RES  100K 1% CHIP  pkg 0402LF  page 134 : 1 = P3V3_AUX ; 2 = HP_LVC3_OCP_V3_1_P12V_PWRGD
R3799  Q_RES  100K 1% CHIP  pkg 0402LF  page 134 : 1 = P3V3_AUX ; 2 = P12V_OCP_FAULT_1
R3807  Q_RES  0 5% CHIP  pkg 0402LF  page 140 : 1 = P3V3_OCP_UV_2_R1 ; 2 = P3V3_OCP_UV_2
R3816  Q_RES  100K 1% CHIP  pkg 0402LF  page 140 : 1 = P3V3_AUX ; 2 = P12V_OCP_FAULT_2
R3825  Q_RES  100K 1% CHIP  pkg 0402LF  page 140 : 1 = P3V3_AUX ; 2 = HP_LVC3_OCP_V3_2_P12V_PWRGD
R3826  Q_RES  100K 1% EMPTY  pkg 0402LF  page 140 : 1 = P3V3_AUX ; 2 = OCP_V3_2_P3V3_PWRGD
R3827  Q_RES  0 5% CHIP  pkg 0402LF  page 140 : 1 = P12V_OCP_UV_2_R ; 2 = P12V_OCP_UV_2
R3831  Q_RES  0 5% CHIP  pkg 0402LF  page 140 : 1 = P12V_OCP_PWRGD_2 ; 2 = HP_LVC3_OCP_V3_2_P12V_PWRGD
R3832  Q_RES  0 5% EMPTY  pkg 0402LF  page 140 : 1 = P3V3_OCP_PWRGD_2 ; 2 = OCP_V3_2_P3V3_PWRGD
R3833  Q_RES  100K 1% CHIP  pkg 0402LF  page 140 : 1 = P3V3_AUX ; 2 = P3V3_OCP_FAULT_2
R3834  Q_RES  0 5% EMPTY  pkg 0402LF  page 135 : 1 = P12V_OCP_SFF_EN_R ; 2 = P12V_OCP_EN_1_R2
R3836  Q_RES  10K 1% CHIP  pkg 0402LF  page 152 : 1 = P3V3_AUX ; 2 = HP_LVC3_SCM_HSC_PWRGD_R
R3845  Q_RES  0 5% EMPTY  pkg 0402LF  page 135 : 1 = P3V3_OCP_SFF_EN_R ; 2 = P3V3_OCP_EN_1_R2
R3848  Q_RES  10K 1% CHIP  pkg 0402LF  page 141 : 1 = P3V3_AUX ; 2 = HP_LVC3_OCP_V3_2_P12V_PWRGD
R3858  Q_RES  33.2 1% CHIP  pkg 0402LF  page 150 : 1 = SMB_OCP_V3_2_3V3AUX_SDA ; 2 = SMB_OCP_V3_2_3V3AUX_SDA_R0
R3859  Q_RES  0 5% EMPTY  pkg 0402LF  page 257 : 1 = P12V_OCP_V3_2_ISENSE_MAM_MAM ; 2 = P12V_OCP_V3_2_ISENSE_MAM
R3860  Q_RES  0 5% EMPTY  pkg 0402LF  page 257 : 1 = P12V_OCP_V3_2_ISENSE_MPS_MAM ; 2 = P12V_OCP_V3_2_ISENSE_MAM
R3861  Q_RES  0 5% CHIP  pkg 0402LF  page 257 : 1 = P12V_OCP_V3_2_ISENSE_MAM_TIC ; 2 = P12V_OCP_V3_2_ISENSE_TIC
R3862  Q_RES  0 5% EMPTY  pkg 0402LF  page 257 : 1 = P12V_OCP_V3_2_ISENSE_MPS_TIC ; 2 = P12V_OCP_V3_2_ISENSE_TIC
R3863  Q_RES  0 5% EMPTY  pkg 0402LF  page 257 : 1 = P12V_OCP_SFF_ISENSE_MAM_MAM ; 2 = P12V_OCP_SFF_ISENSE_MAM
R3864  Q_RES  0 5% EMPTY  pkg 0402LF  page 257 : 1 = P12V_OCP_SFF_ISENSE_MPS_MAM ; 2 = P12V_OCP_SFF_ISENSE_MAM
R3865  Q_RES  0 5% CHIP  pkg 0402LF  page 257 : 1 = P12V_OCP_SFF_ISENSE_MAM_TIC ; 2 = P12V_OCP_SFF_ISENSE_TIC
R3866  Q_RES  0 5% EMPTY  pkg 0402LF  page 257 : 1 = P12V_OCP_SFF_ISENSE_MPS_TIC ; 2 = P12V_OCP_SFF_ISENSE_TIC
R3867  Q_RES  0 5% EMPTY  pkg 0402LF  page 140 : 1 = P12V_OCP_SENSE_2 ; 2 = P12V_OCP_V3_2_ISENSE_MAM_MAM
R3868  Q_RES  0 5% CHIP  pkg 0402LF  page 140 : 1 = P12V_OCP_SENSE_2 ; 2 = P12V_OCP_V3_2_ISENSE_MAM_TIC
R3869  Q_RES  0 5% EMPTY  pkg 0402LF  page 134 : 1 = P12V_OCP_SENSE_1 ; 2 = P12V_OCP_SFF_ISENSE_MAM_MAM
R3870  Q_RES  0 5% CHIP  pkg 0402LF  page 134 : 1 = P12V_OCP_SENSE_1 ; 2 = P12V_OCP_SFF_ISENSE_MAM_TIC
R3871  Q_RES  0 5% CHIP  pkg 0402LF  page 135 : 1 = P12V_OCP_IMON_1 ; 2 = P12V_OCP_SFF_ISENSE_MPS_MAM
R3872  Q_RES  0 5% EMPTY  pkg 0402LF  page 135 : 1 = P12V_OCP_IMON_1 ; 2 = P12V_OCP_SFF_ISENSE_MPS_TIC
R3873  Q_RES  0 5% CHIP  pkg 0402LF  page 141 : 1 = P12V_OCP_IMON_2 ; 2 = P12V_OCP_V3_2_ISENSE_MPS_MAM
R3874  Q_RES  0 5% EMPTY  pkg 0402LF  page 141 : 1 = P12V_OCP_IMON_2 ; 2 = P12V_OCP_V3_2_ISENSE_MPS_TIC
R3907  Q_RES  33K 1% CHIP  pkg 0402LF  page 268 : 1 = PDB_PRSNT_R_N ; 2 = GND
R3909  Q_RES  33.2 1% CHIP  pkg 0402LF  page 262 : 1 = SMB_SML1_PMBUS_HSC_SCL ; 2 = SMB_SML1_PMBUS_HSC_L_SCL
R3923  Q_RES  63.4K 1% CHIP  pkg 0402LF  page 268 : 1 = P12V_PSU_FUSE ; 2 = PDB_PRSNT_R_N
R3924  Q_RES  0 5% CHIP  pkg 0402LF  page 262 : 1 = IRQ_SML1_PMBUS_ALERT_N ; 2 = IRQ_SML1_PMBUS_ALERT
R3925  Q_RES  1K 1% CHIP  pkg 0402LF  page 262 : 1 = IRQ_SML1_PMBUS_ALERT ; 2 = P3V3_AUX
R3933  Q_RES  16.9K 1% CHIP  pkg 0402LF  page 262 : 1 = P12V_AUX ; 2 = MB0_P12V_STBY_PWRGD
R3934  Q_RES  22 1% CHIP  pkg 0402LF  page 262 : 1 = HSC_D_OC_R ; 2 = HSC_D_OC
R3936  Q_RES  4.7K 1% CHIP  pkg 0402LF  page 262 : 1 = HSC_VDD ; 2 = HSC_D_OC
R3939  Q_RES  0 5% EMPTY  pkg 0402LF  page 257 : 1 = P12V_E1S_0_ISENSE_MAM_MAM ; 2 = P12V_E1S_0_ISENSE_MAM
R3940  Q_RES  0 5% EMPTY  pkg 0402LF  page 257 : 1 = P12V_E1S_0_ISENSE_MPS_MAM ; 2 = P12V_E1S_0_ISENSE_MAM
R3941  Q_RES  0 5% CHIP  pkg 0402LF  page 257 : 1 = P12V_E1S_0_ISENSE_MAM_TIC ; 2 = P12V_E1S_0_ISENSE_TIC
R3942  Q_RES  0 5% EMPTY  pkg 0402LF  page 257 : 1 = P12V_E1S_0_ISENSE_MPS_TIC ; 2 = P12V_E1S_0_ISENSE_TIC
R3943  Q_RES  0 5% CHIP  pkg 0402LF  page 147 : 1 = E1S_0_P12V_EN ; 2 = P12V_E1S_EN_0_R2
R3946  Q_RES  0 5% CHIP  pkg 0402LF  page 147 : 1 = E1S_0_P3V3_EN ; 2 = P3V3_E1S_EN_0_R2
R3948  Q_RES  10K 1% CHIP  pkg 0402LF  page 147 : 1 = P3V3_AUX ; 2 = HP_LVC3_E1S_0_HSC_PWRGD
R3955  Q_RES  0 5% CHIP  pkg 0402LF  page 147 : 1 = P12V_E1S_IMON_0 ; 2 = P12V_E1S_0_ISENSE_MPS_MAM
R3956  Q_RES  0 5% EMPTY  pkg 0402LF  page 147 : 1 = P12V_E1S_IMON_0 ; 2 = P12V_E1S_0_ISENSE_MPS_TIC
R3958  Q_RES  0 5% CHIP  pkg 0402LF  page 146 : 1 = P12V_E1S_UV_0_R ; 2 = P12V_E1S_UV_0
R3959  Q_RES  0 5% CHIP  pkg 0402LF  page 146 : 1 = P3V3_E1S_UV_0_R ; 2 = P3V3_E1S_UV_0
R3972  Q_RES  0 5% CHIP  pkg 0402LF  page 146 : 1 = P12V_E1S_PWRGD_0 ; 2 = HP_LVC3_E1S_0_HSC_PWRGD
R3973  Q_RES  0 5% CHIP  pkg 0402LF  page 146 : 1 = P3V3_E1S_PWRGD_0 ; 2 = P3V3_E1S_PWRGD_0_R
R3974  Q_RES  0 5% EMPTY  pkg 0402LF  page 146 : 1 = P12V_E1S_SENSE_0 ; 2 = P12V_E1S_0_ISENSE_MAM_MAM
R3975  Q_RES  0 5% CHIP  pkg 0402LF  page 146 : 1 = P12V_E1S_SENSE_0 ; 2 = P12V_E1S_0_ISENSE_MAM_TIC
R3976  Q_RES  100K 1% CHIP  pkg 0402LF  page 146 : 1 = P3V3_AUX ; 2 = P12V_E1S_FAULT_0
R3977  Q_RES  100K 1% CHIP  pkg 0402LF  page 146 : 1 = P3V3_AUX ; 2 = P3V3_E1S_FAULT_0
R3978  Q_RES  100K 1% CHIP  pkg 0402LF  page 146 : 1 = P3V3_AUX ; 2 = HP_LVC3_E1S_0_HSC_PWRGD
R3979  Q_RES  100K 1% CHIP  pkg 0402LF  page 146 : 1 = P3V3_AUX ; 2 = P3V3_E1S_PWRGD_0_R
R3996  Q_RES  0 5% CHIP  pkg 0402LF  page 152 : 1 = VIRTUAL_RESEAT_FPGA_N ; 2 = P12V_SCM_EN
R3997  Q_RES  0 5% CHIP  pkg 0402LF  page 152 : 1 = P12V_SCM_UV_R ; 2 = P12V_SCM_UV
R3998  Q_RES  0 5% CHIP  pkg 0402LF  page 152 : 1 = P12V_SCM_EN ; 2 = P12V_SCM_EN_R2
R4013  Q_RES  100K 1% CHIP  pkg 0402LF  page 152 : 1 = P3V3_AUX ; 2 = P12V_SCM_FAULT_R_N
R4015  Q_RES  100K 1% CHIP  pkg 0402LF  page 152 : 1 = P3V3_AUX ; 2 = HP_LVC3_SCM_HSC_PWRGD
R4058  Q_RES  10K 1% CHIP  pkg 0402LF  page 123 : 1 = P3V3_AUX ; 2 = PRSNT_SWB_N
R4059  Q_RES  0 5% EMPTY  pkg 0402LF  page 140 : 1 = P12V_OCP_V3_2_EN_R ; 2 = P12V_OCP_EN_2_R
R4060  Q_RES  0 5% EMPTY  pkg 0402LF  page 140 : 1 = P3V3_OCP_V3_2_EN_R ; 2 = P3V3_OCP_EN_2_R
R4061  Q_RES  0 5% EMPTY  pkg 0402LF  page 134 : 1 = P12V_OCP_SFF_EN_R ; 2 = P12V_OCP_EN_1_R
R4062  Q_RES  0 5% CHIP  pkg 0402LF  page 152 : 1 = P12V_SCM_EN ; 2 = P12V_SCM_EN_R
R4063  Q_RES  0 5% CHIP  pkg 0402LF  page 146 : 1 = E1S_0_P3V3_EN ; 2 = P3V3_E1S_EN_0_R
R4064  Q_RES  0 5% CHIP  pkg 0402LF  page 146 : 1 = E1S_0_P12V_EN ; 2 = P12V_E1S_EN_0_R
R4065  Q_RES  10K 1% CHIP  pkg 0402LF  page 140 : 1 = P12V_AUX ; 2 = P12V_OCP_2_EN_G
R4066  Q_RES  4.7K 5% EMPTY  pkg 0402LF  page 140 : 1 = P3V3_OCP_EN_2_R ; 2 = GND
R4067  Q_RES  10K 1% CHIP  pkg 0402LF  page 140 : 1 = P12V_AUX ; 2 = P3V3_OCP_2_EN_G
R4068  Q_RES  10K 1% CHIP  pkg 0402LF  page 134 : 1 = P12V_AUX ; 2 = P12V_OCP_1_EN_G
R4069  Q_RES  4.7K 5% EMPTY  pkg 0402LF  page 134 : 1 = P3V3_OCP_EN_1_R ; 2 = GND
R4070  Q_RES  10K 1% CHIP  pkg 0402LF  page 134 : 1 = P12V_AUX ; 2 = P3V3_OCP_1_EN_G
R4071  Q_RES  10K 1% CHIP  pkg 0402LF  page 152 : 1 = P12V_AUX ; 2 = P12V_SCM_EN_G
R4072  Q_RES  10K 1% CHIP  pkg 0402LF  page 146 : 1 = P12V_AUX ; 2 = P3V3_E1S_0_EN_G
R4073  Q_RES  4.7K 5% CHIP  pkg 0402LF  page 146 : 1 = P12V_E1S_EN_0_R ; 2 = GND
R4074  Q_RES  10K 1% CHIP  pkg 0402LF  page 146 : 1 = P12V_AUX ; 2 = P12V_E1S_0_EN_G
R4075  Q_RES  0 5% CHIP  pkg 0402LF  page 233 : 1 = CLK_GEN2_BMC_RC_OE_N ; 2 = CLK_GEN2_BMC_RC_OE_R3_N
R4076  Q_RES  0 5% CHIP  pkg 0402LF  page 233 : 1 = CLK_GEN2_GPU_FPGA_OE_OR_N ; 2 = CLK_GEN2_GPU_OE_N
R4077  Q_RES  1 1% CHIP  pkg 0402LF  page 233 : 1 = VFG3P3_CLK_GEN ; 2 = VFG_3P3A_CLK_GEN
R4078  Q_RES  10K 1% EMPTY  pkg 0402LF  page 233 : 1 = P3V3_AUX ; 2 = FG_SS_EN
R4079  Q_RES  10K 1% CHIP  pkg 0402LF  page 233 : 1 = FG_SS_EN ; 2 = GND
R4080  Q_RES  10K 1% CHIP  pkg 0402LF  page 233 : 1 = P3V3_AUX ; 2 = P3V3_PWRGD_CLKGEN
R4081  Q_RES  10K 1% CHIP  pkg 0402LF  page 233 : 1 = P3V3_AUX ; 2 = CLK_GEN2_SMB_SADR
R4082  Q_RES  10K 1% EMPTY  pkg 0402LF  page 233 : 1 = CLK_GEN2_SMB_SADR ; 2 = GND
R4087  Q_RES  0 5% CHIP  pkg 0402LF  page 150 : 1 = FW_RECOVERY_R ; 2 = FW_RECOVERY
R4090  Q_RES  1K 1% CHIP  pkg 0402LF  page 237 : 1 = P3V3_AUX ; 2 = M2_0_P3V3_ADC_ALERT_R
R4091  Q_RES  1K 1% CHIP  pkg 0402LF  page 237 : 1 = P3V3_AUX ; 2 = P12V_SCM_ADC_ALERT_R
R4092  Q_RES  1K 1% CHIP  pkg 0402LF  page 237 : 1 = P3V3_AUX ; 2 = OCP_V3_2_P3V3_ADC_ALERT_R
R4093  Q_RES  1K 1% CHIP  pkg 0402LF  page 236 : 1 = P3V3_AUX ; 2 = E1S_0_P3V3_ADC_ALERT_R
R4094  Q_RES  1K 1% CHIP  pkg 0402LF  page 236 : 1 = P3V3_AUX ; 2 = OCP_SFF_P3V3_ADC_ALERT_R
